# T6G (Grand Teton) — schematic netlist excerpt (pin names and nets, part order shuffled) for the footprints in the layout excerpt that follows; sources: Cadence DE-HDL packaged netlist, KiCad conversion of 04192023_DAF0TMB3IC0_F0TG_MB_C_brd_V02_OCP.brd

R4549  Q_RES  4.7K 5% EMPTY  pkg 0402LF  page 124 : A = P3V3_AUX ; B = SWB_HSC_EN_BUF_R
TP3  TP  NA  pkg TP  page 27 : TP = VSENSE_VSS_SENSE_C_P0
PC2079  Q_CAP  1UF 25V 10% X6S  pkg C0402  page 134 : A = P12V_AUX ; B = GND
R875  Q_RES  10K 1% CHIP  pkg 0201LF  page 342 : A = GPIO2_RT_CPU1_P2 ; B = GND

(kicad_pcb
	(version 20260206)
	(generator "pcbnew")
	(generator_version "10.0")
	(general
		(thickness 1.6)
		(legacy_teardrops no)
	)
	(paper "A4")
	(title_block
		(title "04192023_DAF0TMB3IC0_F0TG_MB_C_brd_V02_OCP.brd")
		(comment 1 "Grand Teton / footprints 3173-3176 of 8354")
	)
	(layers
		(0 "F.Cu" signal "TOP")
		(4 "In1.Cu" signal "GND")
		(6 "In2.Cu" signal "IN1")
		(8 "In3.Cu" signal "GND1")
		(10 "In4.Cu" signal "IN2")
		(12 "In5.Cu" signal "GND2")
		(14 "In6.Cu" signal "IN3")
		(16 "In7.Cu" signal "GND3")
		(18 "In8.Cu" signal "VCC")
		(20 "In9.Cu" signal "VCC1")
		(22 "In10.Cu" signal "GND4")
		(24 "In11.Cu" signal "IN4")
		(26 "In12.Cu" signal "GND5")
		(28 "In13.Cu" signal "IN5")
		(30 "In14.Cu" signal "GND6")
		(32 "In15.Cu" signal "IN6")
		(34 "In16.Cu" signal "GND7")
		(2 "B.Cu" signal "BOTTOM")
		(9 "F.Adhes" user "F.Adhesive")
		(11 "B.Adhes" user "B.Adhesive")
		(13 "F.Paste" user "Package Geometry/Pastemask Top")
		(15 "B.Paste" user "Package Geometry/Pastemask Bottom")
		(5 "F.SilkS" user "Ref Des/Silkscreen Top")
		(7 "B.SilkS" user "Ref Des/Silkscreen Bottom")
		(1 "F.Mask" user "Board Geometry/Soldermask Top")
		(3 "B.Mask" user "Board Geometry/Soldermask Bottom")
		(17 "Dwgs.User" user "User.Drawings")
		(19 "Cmts.User" user "User.Comments")
		(21 "Eco1.User" user "User.Eco1")
		(23 "Eco2.User" user "User.Eco2")
		(25 "Edge.Cuts" user "Board Geometry/Outline")
		(27 "Margin" user)
		(31 "F.CrtYd" user "Package Geometry/Place Bound Top")
		(29 "B.CrtYd" user "Package Geometry/Place Bound Bottom")
		(35 "F.Fab" user "Ref Des/Assembly Top")
		(33 "B.Fab" user "Ref Des/Assembly Bottom")
	)
	(footprint ""
		(layer "F.Cu")
		(at 358.384094 -325.310754 180)
		(property "Reference" "TP3"
			(at -0.90424 -0.772668 0)
			(unlocked yes)
			(layer "F.SilkS")
			(effects
				(font
					(size 0.7874 0.5842)
					(thickness 0.1524)
				)
				(justify left)
			)
		)
		(property "Value" ""
			(at 0 0 180)
			(layer "F.Fab")
			(effects
				(font
					(size 1.27 1.27)
				)
			)
		)
		(duplicate_pad_numbers_are_jumpers no)
		(pad "1" smd circle
			(at 0 0 180)
			(size 0.762 0.762)
			(layers "F.Cu" "F.Mask" "F.Paste")
			(net "VSENSE_VSS_SENSE_C_P0")
		)
	)
	(footprint ""
		(layer "F.Cu")
		(at 142.893542 -385.58216)
		(property "Reference" "R875"
			(at 0 0 0)
			(layer "F.SilkS")
			(hide yes)
			(effects
				(font
					(size 1.27 1.27)
				)
			)
		)
		(property "Value" ""
			(at 0 0 0)
			(layer "F.Fab")
			(effects
				(font
					(size 1.27 1.27)
				)
			)
		)
		(duplicate_pad_numbers_are_jumpers no)
		(fp_line
			(start -0.32512 -0.175006)
			(end 0.32512 -0.175006)
			(stroke
				(width 0.1)
				(type default)
			)
			(layer "F.Fab")
		)
		(fp_line
			(start -0.32512 0.175006)
			(end -0.32512 -0.175006)
			(stroke
				(width 0.1)
				(type default)
			)
			(layer "F.Fab")
		)
		(fp_line
			(start 0.32512 -0.175006)
			(end 0.32512 0.175006)
			(stroke
				(width 0.1)
				(type default)
			)
			(layer "F.Fab")
		)
		(fp_line
			(start 0.32512 0.175006)
			(end -0.32512 0.175006)
			(stroke
				(width 0.1)
				(type default)
			)
			(layer "F.Fab")
		)
		(pad "1" smd rect
			(at -0.2667 0)
			(size 0.3048 0.381)
			(layers "F.Cu" "F.Mask" "F.Paste")
			(net "GPIO2_RT_CPU1_P2")
		)
		(pad "2" smd rect
			(at 0.2667 0 180)
			(size 0.3048 0.381)
			(layers "F.Cu" "F.Mask" "F.Paste")
			(net "GND")
		)
	)
	(footprint ""
		(layer "F.Cu")
		(at 352.05543 -432.825652)
		(property "Reference" "R4549"
			(at 0 0 0)
			(layer "F.SilkS")
			(hide yes)
			(effects
				(font
					(size 1.27 1.27)
				)
			)
		)
		(property "Value" ""
			(at 0 0 0)
			(layer "F.Fab")
			(effects
				(font
					(size 1.27 1.27)
				)
			)
		)
		(duplicate_pad_numbers_are_jumpers no)
		(fp_line
			(start -0.7874 -0.4064)
			(end 0.7874 -0.4064)
			(stroke
				(width 0.1524)
				(type default)
			)
			(layer "F.SilkS")
		)
		(fp_line
			(start -0.7874 0.4064)
			(end -0.7874 -0.4064)
			(stroke
				(width 0.1524)
				(type default)
			)
			(layer "F.SilkS")
		)
		(fp_line
			(start 0.7874 -0.4064)
			(end 0.7874 0.4064)
			(stroke
				(width 0.1524)
				(type default)
			)
			(layer "F.SilkS")
		)
		(fp_line
			(start 0.7874 0.4064)
			(end -0.7874 0.4064)
			(stroke
				(width 0.1524)
				(type default)
			)
			(layer "F.SilkS")
		)
		(fp_line
			(start -0.67945 -0.305054)
			(end -0.12065 -0.305054)
			(stroke
				(width 0.1)
				(type default)
			)
			(layer "F.Fab")
		)
		(fp_line
			(start -0.67945 0.3048)
			(end -0.67945 -0.305054)
			(stroke
				(width 0.1)
				(type default)
			)
			(layer "F.Fab")
		)
		(fp_line
			(start -0.12065 -0.305054)
			(end -0.12065 -0.2794)
			(stroke
				(width 0.1)
				(type default)
			)
			(layer "F.Fab")
		)
		(fp_line
			(start -0.12065 -0.2794)
			(end 0.12065 -0.2794)
			(stroke
				(width 0.1)
				(type default)
			)
			(layer "F.Fab")
		)
		(fp_line
			(start -0.12065 0.2794)
			(end -0.12065 0.3048)
			(stroke
				(width 0.1)
				(type default)
			)
			(layer "F.Fab")
		)
		(fp_line
			(start -0.12065 0.3048)
			(end -0.67945 0.3048)
			(stroke
				(width 0.1)
				(type default)
			)
			(layer "F.Fab")
		)
		(fp_line
			(start 0.120396 0.2794)
			(end -0.12065 0.2794)
			(stroke
				(width 0.1)
				(type default)
			)
			(layer "F.Fab")
		)
		(fp_line
			(start 0.120396 0.3048)
			(end 0.120396 0.2794)
			(stroke
				(width 0.1)
				(type default)
			)
			(layer "F.Fab")
		)
		(fp_line
			(start 0.12065 -0.3048)
			(end 0.67945 -0.3048)
			(stroke
				(width 0.1)
				(type default)
			)
			(layer "F.Fab")
		)
		(fp_line
			(start 0.12065 -0.2794)
			(end 0.12065 -0.3048)
			(stroke
				(width 0.1)
				(type default)
			)
			(layer "F.Fab")
		)
		(fp_line
			(start 0.67945 -0.3048)
			(end 0.67945 0.3048)
			(stroke
				(width 0.1)
				(type default)
			)
			(layer "F.Fab")
		)
		(fp_line
			(start 0.67945 0.3048)
			(end 0.120396 0.3048)
			(stroke
				(width 0.1)
				(type default)
			)
			(layer "F.Fab")
		)
		(pad "1" smd circle
			(at -0.40005 0)
			(size 0 0)
			(layers "F.Cu" "F.Mask" "F.Paste")
			(net "P3V3_AUX")
		)
		(pad "2" smd circle
			(at 0.40005 0)
			(size 0 0)
			(layers "F.Cu" "F.Mask" "F.Paste")
			(net "SWB_HSC_EN_BUF_R")
		)
	)
	(footprint ""
		(layer "F.Cu")
		(at 449.044314 -25.10028 -90)
		(property "Reference" "PC2079"
			(at 0 0 270)
			(layer "F.SilkS")
			(hide yes)
			(effects
				(font
					(size 1.27 1.27)
				)
			)
		)
		(property "Value" ""
			(at 0 0 270)
			(layer "F.Fab")
			(effects
				(font
					(size 1.27 1.27)
				)
			)
		)
		(duplicate_pad_numbers_are_jumpers no)
		(fp_line
			(start -0.7874 0.4064)
			(end -0.7874 -0.4064)
			(stroke
				(width 0.1524)
				(type default)
			)
			(layer "F.SilkS")
		)
		(fp_line
			(start 0.7874 0.4064)
			(end -0.7874 0.4064)
			(stroke
				(width 0.1524)
				(type default)
			)
			(layer "F.SilkS")
		)
		(fp_line
			(start -0.7874 -0.4064)
			(end 0.7874 -0.4064)
			(stroke
				(width 0.1524)
				(type default)
			)
			(layer "F.SilkS")
		)
		(fp_line
			(start 0.7874 -0.4064)
			(end 0.7874 0.4064)
			(stroke
				(width 0.1524)
				(type default)
			)
			(layer "F.SilkS")
		)
		(fp_line
			(start -0.67945 0.3048)
			(end -0.67945 -0.305054)
			(stroke
				(width 0.1)
				(type default)
			)
			(layer "F.Fab")
		)
		(fp_line
			(start -0.12065 0.3048)
			(end -0.67945 0.3048)
			(stroke
				(width 0.1)
				(type default)
			)
			(layer "F.Fab")
		)
		(fp_line
			(start 0.120396 0.3048)
			(end 0.120396 0.2794)
			(stroke
				(width 0.1)
				(type default)
			)
			(layer "F.Fab")
		)
		(fp_line
			(start 0.67945 0.3048)
			(end 0.120396 0.3048)
			(stroke
				(width 0.1)
				(type default)
			)
			(layer "F.Fab")
		)
		(fp_line
			(start -0.12065 0.2794)
			(end -0.12065 0.3048)
			(stroke
				(width 0.1)
				(type default)
			)
			(layer "F.Fab")
		)
		(fp_line
			(start 0.120396 0.2794)
			(end -0.12065 0.2794)
			(stroke
				(width 0.1)
				(type default)
			)
			(layer "F.Fab")
		)
		(fp_line
			(start -0.12065 -0.2794)
			(end 0.12065 -0.2794)
			(stroke
				(width 0.1)
				(type default)
			)
			(layer "F.Fab")
		)
		(fp_line
			(start 0.12065 -0.2794)
			(end 0.12065 -0.3048)
			(stroke
				(width 0.1)
				(type default)
			)
			(layer "F.Fab")
		)
		(fp_line
			(start 0.12065 -0.3048)
			(end 0.67945 -0.3048)
			(stroke
				(width 0.1)
				(type default)
			)
			(layer "F.Fab")
		)
		(fp_line
			(start 0.67945 -0.3048)
			(end 0.67945 0.3048)
			(stroke
				(width 0.1)
				(type default)
			)
			(layer "F.Fab")
		)
		(fp_line
			(start -0.67945 -0.305054)
			(end -0.12065 -0.305054)
			(stroke
				(width 0.1)
				(type default)
			)
			(layer "F.Fab")
		)
		(fp_line
			(start -0.12065 -0.305054)
			(end -0.12065 -0.2794)
			(stroke
				(width 0.1)
				(type default)
			)
			(layer "F.Fab")
		)
		(pad "1" smd circle
			(at -0.40005 0 270)
			(size 0 0)
			(layers "F.Cu" "F.Mask" "F.Paste")
			(net "P12V_AUX")
		)
		(pad "2" smd circle
			(at 0.40005 0 270)
			(size 0 0)
			(layers "F.Cu" "F.Mask" "F.Paste")
			(net "GND")
		)
	)
)
